# S9S_MB_2U (Grand Teton) — schematic netlist excerpt (pin names and nets, part order shuffled) for the footprints in the layout excerpt that follows; sources: Cadence DE-HDL packaged netlist, KiCad conversion of 03242023_DA0F0TMBIJ0_F0T_Motherboard_J_brd_V01_OCP.brd

D79  Q_LED  IC  pkg SMLF  page 253 : A = LED_PWRGD_PVCCIN_CPU0 ; C = LED_PWRGD_PVCCIN_CPU0_D
R1340  Q_RES  20K 1% CHIP  pkg 0402LF  page 201 : A = P3V3_RTC_AUX ; B = RST_RTCRST_N

(kicad_pcb
	(version 20260206)
	(generator "pcbnew")
	(generator_version "10.0")
	(general
		(thickness 1.6)
		(legacy_teardrops no)
	)
	(paper "A4")
	(title_block
		(title "03242023_DA0F0TMBIJ0_F0T_Motherboard_J_brd_V01_OCP.brd")
		(comment 1 "Grand Teton / footprints 2618-2619 of 6105")
	)
	(layers
		(0 "F.Cu" signal "TOP")
		(4 "In1.Cu" signal "GND")
		(6 "In2.Cu" signal "IN1")
		(8 "In3.Cu" signal "GND1")
		(10 "In4.Cu" signal "IN2")
		(12 "In5.Cu" signal "GND2")
		(14 "In6.Cu" signal "IN3")
		(16 "In7.Cu" signal "GND3")
		(18 "In8.Cu" signal "VCC")
		(20 "In9.Cu" signal "VCC1")
		(22 "In10.Cu" signal "GND4")
		(24 "In11.Cu" signal "IN4")
		(26 "In12.Cu" signal "GND5")
		(28 "In13.Cu" signal "IN5")
		(30 "In14.Cu" signal "GND6")
		(32 "In15.Cu" signal "IN6")
		(34 "In16.Cu" signal "GND7")
		(2 "B.Cu" signal "BOTTOM")
		(9 "F.Adhes" user "F.Adhesive")
		(11 "B.Adhes" user "B.Adhesive")
		(13 "F.Paste" user "Package Geometry/Pastemask Top")
		(15 "B.Paste" user "Package Geometry/Pastemask Bottom")
		(5 "F.SilkS" user "Ref Des/Silkscreen Top")
		(7 "B.SilkS" user "Ref Des/Silkscreen Bottom")
		(1 "F.Mask" user "Board Geometry/Soldermask Top")
		(3 "B.Mask" user "Board Geometry/Soldermask Bottom")
		(17 "Dwgs.User" user "User.Drawings")
		(19 "Cmts.User" user "User.Comments")
		(21 "Eco1.User" user "User.Eco1")
		(23 "Eco2.User" user "User.Eco2")
		(25 "Edge.Cuts" user "Board Geometry/Outline")
		(27 "Margin" user)
		(31 "F.CrtYd" user "Package Geometry/Place Bound Top")
		(29 "B.CrtYd" user "Package Geometry/Place Bound Bottom")
		(35 "F.Fab" user "Ref Des/Assembly Top")
		(33 "B.Fab" user "Ref Des/Assembly Bottom")
	)
	(footprint ""
		(layer "F.Cu")
		(at 302.566324 -34.937446 90)
		(property "Reference" "R1340"
			(at 0 0 90)
			(layer "F.SilkS")
			(hide yes)
			(effects
				(font
					(size 1.27 1.27)
				)
			)
		)
		(property "Value" ""
			(at 0 0 90)
			(layer "F.Fab")
			(effects
				(font
					(size 1.27 1.27)
				)
			)
		)
		(duplicate_pad_numbers_are_jumpers no)
		(fp_line
			(start 0.7874 -0.4064)
			(end 0.7874 0.4064)
			(stroke
				(width 0.1524)
				(type default)
			)
			(layer "F.SilkS")
		)
		(fp_line
			(start -0.7874 -0.4064)
			(end 0.7874 -0.4064)
			(stroke
				(width 0.1524)
				(type default)
			)
			(layer "F.SilkS")
		)
		(fp_line
			(start 0.7874 0.4064)
			(end -0.7874 0.4064)
			(stroke
				(width 0.1524)
				(type default)
			)
			(layer "F.SilkS")
		)
		(fp_line
			(start -0.7874 0.4064)
			(end -0.7874 -0.4064)
			(stroke
				(width 0.1524)
				(type default)
			)
			(layer "F.SilkS")
		)
		(fp_line
			(start -0.12065 -0.305054)
			(end -0.12065 -0.2794)
			(stroke
				(width 0.1)
				(type default)
			)
			(layer "F.Fab")
		)
		(fp_line
			(start -0.67945 -0.305054)
			(end -0.12065 -0.305054)
			(stroke
				(width 0.1)
				(type default)
			)
			(layer "F.Fab")
		)
		(fp_line
			(start 0.67945 -0.3048)
			(end 0.67945 0.3048)
			(stroke
				(width 0.1)
				(type default)
			)
			(layer "F.Fab")
		)
		(fp_line
			(start 0.12065 -0.3048)
			(end 0.67945 -0.3048)
			(stroke
				(width 0.1)
				(type default)
			)
			(layer "F.Fab")
		)
		(fp_line
			(start 0.12065 -0.2794)
			(end 0.12065 -0.3048)
			(stroke
				(width 0.1)
				(type default)
			)
			(layer "F.Fab")
		)
		(fp_line
			(start -0.12065 -0.2794)
			(end 0.12065 -0.2794)
			(stroke
				(width 0.1)
				(type default)
			)
			(layer "F.Fab")
		)
		(fp_line
			(start 0.120396 0.2794)
			(end -0.12065 0.2794)
			(stroke
				(width 0.1)
				(type default)
			)
			(layer "F.Fab")
		)
		(fp_line
			(start -0.12065 0.2794)
			(end -0.12065 0.3048)
			(stroke
				(width 0.1)
				(type default)
			)
			(layer "F.Fab")
		)
		(fp_line
			(start 0.67945 0.3048)
			(end 0.120396 0.3048)
			(stroke
				(width 0.1)
				(type default)
			)
			(layer "F.Fab")
		)
		(fp_line
			(start 0.120396 0.3048)
			(end 0.120396 0.2794)
			(stroke
				(width 0.1)
				(type default)
			)
			(layer "F.Fab")
		)
		(fp_line
			(start -0.12065 0.3048)
			(end -0.67945 0.3048)
			(stroke
				(width 0.1)
				(type default)
			)
			(layer "F.Fab")
		)
		(fp_line
			(start -0.67945 0.3048)
			(end -0.67945 -0.305054)
			(stroke
				(width 0.1)
				(type default)
			)
			(layer "F.Fab")
		)
		(pad "1" smd circle
			(at -0.40005 0 90)
			(size 0 0)
			(layers "F.Cu" "F.Mask" "F.Paste")
			(net "P3V3_RTC_AUX")
		)
		(pad "2" smd circle
			(at 0.40005 0 90)
			(size 0 0)
			(layers "F.Cu" "F.Mask" "F.Paste")
			(net "RST_RTCRST_N")
		)
	)
	(footprint ""
		(layer "F.Cu")
		(at 100.183696 -70.78599)
		(property "Reference" "D79"
			(at -50.276506 50.178462 90)
			(unlocked yes)
			(layer "F.SilkS")
			(effects
				(font
					(size 0.635 0.4064)
					(thickness 0.1524)
				)
				(justify left)
			)
		)
		(property "Value" ""
			(at 0 0 0)
			(layer "F.Fab")
			(effects
				(font
					(size 1.27 1.27)
				)
			)
		)
		(duplicate_pad_numbers_are_jumpers no)
		(fp_line
			(start -0.90678 0.4826)
			(end -0.90678 -0.4699)
			(stroke
				(width 0.1524)
				(type default)
			)
			(layer "F.SilkS")
		)
		(fp_line
			(start -0.89408 -0.4826)
			(end 0.90678 -0.4826)
			(stroke
				(width 0.1524)
				(type default)
			)
			(layer "F.SilkS")
		)
		(fp_line
			(start -0.79248 -0.4826)
			(end 1.03378 -0.4826)
			(stroke
				(width 0.1524)
				(type default)
			)
			(layer "F.SilkS")
		)
		(fp_line
			(start -0.64008 -0.4826)
			(end 1.16078 -0.4826)
			(stroke
				(width 0.1524)
				(type default)
			)
			(layer "F.SilkS")
		)
		(fp_line
			(start 0.90678 -0.4826)
			(end 0.90678 0.4826)
			(stroke
				(width 0.1524)
				(type default)
			)
			(layer "F.SilkS")
		)
		(fp_line
			(start 0.90678 0.4826)
			(end -0.90678 0.4826)
			(stroke
				(width 0.1524)
				(type default)
			)
			(layer "F.SilkS")
		)
		(fp_line
			(start 1.03378 -0.4826)
			(end 1.03378 0.4826)
			(stroke
				(width 0.1524)
				(type default)
			)
			(layer "F.SilkS")
		)
		(fp_line
			(start 1.03378 0.4826)
			(end -0.79248 0.4826)
			(stroke
				(width 0.1524)
				(type default)
			)
			(layer "F.SilkS")
		)
		(fp_line
			(start 1.16078 -0.4826)
			(end 1.16078 0.4826)
			(stroke
				(width 0.1524)
				(type default)
			)
			(layer "F.SilkS")
		)
		(fp_line
			(start 1.16078 0.4826)
			(end -0.64008 0.4826)
			(stroke
				(width 0.1524)
				(type default)
			)
			(layer "F.SilkS")
		)
		(fp_line
			(start -0.499872 -0.249936)
			(end 0.499872 -0.249936)
			(stroke
				(width 0.1)
				(type default)
			)
			(layer "F.Fab")
		)
		(fp_line
			(start -0.499872 0.249936)
			(end -0.499872 -0.249936)
			(stroke
				(width 0.1)
				(type default)
			)
			(layer "F.Fab")
		)
		(fp_line
			(start 0.499872 -0.249936)
			(end 0.499872 0.249936)
			(stroke
				(width 0.1)
				(type default)
			)
			(layer "F.Fab")
		)
		(fp_line
			(start 0.499872 0.249936)
			(end -0.499872 0.249936)
			(stroke
				(width 0.1)
				(type default)
			)
			(layer "F.Fab")
		)
		(pad "A" smd rect
			(at -0.47498 0)
			(size 0.6096 0.7112)
			(layers "F.Cu" "F.Mask" "F.Paste")
			(net "LED_PWRGD_PVCCIN_CPU0")
		)
		(pad "C" smd rect
			(at 0.47498 0)
			(size 0.6096 0.7112)
			(layers "F.Cu" "F.Mask" "F.Paste")
			(net "LED_PWRGD_PVCCIN_CPU0_D")
		)
	)
)
